# T6G (Grand Teton) — schematic netlist excerpt (pin names and nets, part order shuffled) for the footprints in the layout excerpt that follows; sources: Cadence DE-HDL packaged netlist, KiCad conversion of 04192023_DAF0TMB3IC0_F0TG_MB_C_brd_V02_OCP.brd

C1056  Q_CAP  4.7UF 6.3V 20% X6S  pkg 0402  page 312 : A = P0V9_CPU0_RT3_2A ; B = GND
PR441  Q_RES  0 5% CHIP  pkg 0402LF  page 193 : A = NC_PVDDCR_CPU0_P0_IMON9 ; B = GND

(kicad_pcb
	(version 20260206)
	(generator "pcbnew")
	(generator_version "10.0")
	(general
		(thickness 1.6)
		(legacy_teardrops no)
	)
	(paper "A4")
	(title_block
		(title "04192023_DAF0TMB3IC0_F0TG_MB_C_brd_V02_OCP.brd")
		(comment 1 "Grand Teton / footprints 5461-5462 of 8354")
	)
	(layers
		(0 "F.Cu" signal "TOP")
		(4 "In1.Cu" signal "GND")
		(6 "In2.Cu" signal "IN1")
		(8 "In3.Cu" signal "GND1")
		(10 "In4.Cu" signal "IN2")
		(12 "In5.Cu" signal "GND2")
		(14 "In6.Cu" signal "IN3")
		(16 "In7.Cu" signal "GND3")
		(18 "In8.Cu" signal "VCC")
		(20 "In9.Cu" signal "VCC1")
		(22 "In10.Cu" signal "GND4")
		(24 "In11.Cu" signal "IN4")
		(26 "In12.Cu" signal "GND5")
		(28 "In13.Cu" signal "IN5")
		(30 "In14.Cu" signal "GND6")
		(32 "In15.Cu" signal "IN6")
		(34 "In16.Cu" signal "GND7")
		(2 "B.Cu" signal "BOTTOM")
		(9 "F.Adhes" user "F.Adhesive")
		(11 "B.Adhes" user "B.Adhesive")
		(13 "F.Paste" user "Package Geometry/Pastemask Top")
		(15 "B.Paste" user "Package Geometry/Pastemask Bottom")
		(5 "F.SilkS" user "Ref Des/Silkscreen Top")
		(7 "B.SilkS" user "Ref Des/Silkscreen Bottom")
		(1 "F.Mask" user "Board Geometry/Soldermask Top")
		(3 "B.Mask" user "Board Geometry/Soldermask Bottom")
		(17 "Dwgs.User" user "User.Drawings")
		(19 "Cmts.User" user "User.Comments")
		(21 "Eco1.User" user "User.Eco1")
		(23 "Eco2.User" user "User.Eco2")
		(25 "Edge.Cuts" user "Board Geometry/Outline")
		(27 "Margin" user)
		(31 "F.CrtYd" user "Package Geometry/Place Bound Top")
		(29 "B.CrtYd" user "Package Geometry/Place Bound Bottom")
		(35 "F.Fab" user "Ref Des/Assembly Top")
		(33 "B.Fab" user "Ref Des/Assembly Bottom")
	)
	(footprint ""
		(layer "B.Cu")
		(at 372.891304 -398.942052 90)
		(property "Reference" "C1056"
			(at 0 0 90)
			(layer "B.SilkS")
			(hide yes)
			(effects
				(font
					(size 1.27 1.27)
				)
				(justify mirror)
			)
		)
		(property "Value" ""
			(at 0 0 90)
			(layer "B.Fab")
			(effects
				(font
					(size 1.27 1.27)
				)
				(justify mirror)
			)
		)
		(duplicate_pad_numbers_are_jumpers no)
		(fp_line
			(start 0.7874 -0.4064)
			(end -0.7874 -0.4064)
			(stroke
				(width 0.1524)
				(type default)
			)
			(layer "B.SilkS")
		)
		(fp_line
			(start -0.7874 -0.4064)
			(end -0.7874 0.4064)
			(stroke
				(width 0.1524)
				(type default)
			)
			(layer "B.SilkS")
		)
		(fp_line
			(start 0.7874 0.4064)
			(end 0.7874 -0.4064)
			(stroke
				(width 0.1524)
				(type default)
			)
			(layer "B.SilkS")
		)
		(fp_line
			(start -0.7874 0.4064)
			(end 0.7874 0.4064)
			(stroke
				(width 0.1524)
				(type default)
			)
			(layer "B.SilkS")
		)
		(fp_line
			(start 0.67945 -0.305054)
			(end 0.12065 -0.305054)
			(stroke
				(width 0.1)
				(type default)
			)
			(layer "B.Fab")
		)
		(fp_line
			(start 0.12065 -0.305054)
			(end 0.12065 -0.2794)
			(stroke
				(width 0.1)
				(type default)
			)
			(layer "B.Fab")
		)
		(fp_line
			(start -0.12065 -0.3048)
			(end -0.67945 -0.3048)
			(stroke
				(width 0.1)
				(type default)
			)
			(layer "B.Fab")
		)
		(fp_line
			(start -0.67945 -0.3048)
			(end -0.67945 0.3048)
			(stroke
				(width 0.1)
				(type default)
			)
			(layer "B.Fab")
		)
		(fp_line
			(start 0.12065 -0.2794)
			(end -0.12065 -0.2794)
			(stroke
				(width 0.1)
				(type default)
			)
			(layer "B.Fab")
		)
		(fp_line
			(start -0.12065 -0.2794)
			(end -0.12065 -0.3048)
			(stroke
				(width 0.1)
				(type default)
			)
			(layer "B.Fab")
		)
		(fp_line
			(start 0.12065 0.2794)
			(end 0.12065 0.3048)
			(stroke
				(width 0.1)
				(type default)
			)
			(layer "B.Fab")
		)
		(fp_line
			(start -0.120396 0.2794)
			(end 0.12065 0.2794)
			(stroke
				(width 0.1)
				(type default)
			)
			(layer "B.Fab")
		)
		(fp_line
			(start 0.67945 0.3048)
			(end 0.67945 -0.305054)
			(stroke
				(width 0.1)
				(type default)
			)
			(layer "B.Fab")
		)
		(fp_line
			(start 0.12065 0.3048)
			(end 0.67945 0.3048)
			(stroke
				(width 0.1)
				(type default)
			)
			(layer "B.Fab")
		)
		(fp_line
			(start -0.120396 0.3048)
			(end -0.120396 0.2794)
			(stroke
				(width 0.1)
				(type default)
			)
			(layer "B.Fab")
		)
		(fp_line
			(start -0.67945 0.3048)
			(end -0.120396 0.3048)
			(stroke
				(width 0.1)
				(type default)
			)
			(layer "B.Fab")
		)
		(pad "1" smd circle
			(at 0.40005 0 270)
			(size 0 0)
			(layers "B.Cu" "B.Mask" "B.Paste")
			(net "P0V9_CPU0_RT3_2A")
		)
		(pad "2" smd circle
			(at -0.40005 0 270)
			(size 0 0)
			(layers "B.Cu" "B.Mask" "B.Paste")
			(net "GND")
		)
	)
	(footprint ""
		(layer "B.Cu")
		(at 381.645922 -148.30171 -90)
		(property "Reference" "PR441"
			(at 0 0 90)
			(layer "B.SilkS")
			(hide yes)
			(effects
				(font
					(size 1.27 1.27)
				)
				(justify mirror)
			)
		)
		(property "Value" ""
			(at 0 0 90)
			(layer "B.Fab")
			(effects
				(font
					(size 1.27 1.27)
				)
				(justify mirror)
			)
		)
		(duplicate_pad_numbers_are_jumpers no)
		(fp_line
			(start -0.7874 0.4064)
			(end 0.7874 0.4064)
			(stroke
				(width 0.1524)
				(type default)
			)
			(layer "B.SilkS")
		)
		(fp_line
			(start 0.7874 0.4064)
			(end 0.7874 -0.4064)
			(stroke
				(width 0.1524)
				(type default)
			)
			(layer "B.SilkS")
		)
		(fp_line
			(start -0.7874 -0.4064)
			(end -0.7874 0.4064)
			(stroke
				(width 0.1524)
				(type default)
			)
			(layer "B.SilkS")
		)
		(fp_line
			(start 0.7874 -0.4064)
			(end -0.7874 -0.4064)
			(stroke
				(width 0.1524)
				(type default)
			)
			(layer "B.SilkS")
		)
		(fp_line
			(start -0.67945 0.3048)
			(end -0.120396 0.3048)
			(stroke
				(width 0.1)
				(type default)
			)
			(layer "B.Fab")
		)
		(fp_line
			(start -0.120396 0.3048)
			(end -0.120396 0.2794)
			(stroke
				(width 0.1)
				(type default)
			)
			(layer "B.Fab")
		)
		(fp_line
			(start 0.12065 0.3048)
			(end 0.67945 0.3048)
			(stroke
				(width 0.1)
				(type default)
			)
			(layer "B.Fab")
		)
		(fp_line
			(start 0.67945 0.3048)
			(end 0.67945 -0.305054)
			(stroke
				(width 0.1)
				(type default)
			)
			(layer "B.Fab")
		)
		(fp_line
			(start -0.120396 0.2794)
			(end 0.12065 0.2794)
			(stroke
				(width 0.1)
				(type default)
			)
			(layer "B.Fab")
		)
		(fp_line
			(start 0.12065 0.2794)
			(end 0.12065 0.3048)
			(stroke
				(width 0.1)
				(type default)
			)
			(layer "B.Fab")
		)
		(fp_line
			(start -0.12065 -0.2794)
			(end -0.12065 -0.3048)
			(stroke
				(width 0.1)
				(type default)
			)
			(layer "B.Fab")
		)
		(fp_line
			(start 0.12065 -0.2794)
			(end -0.12065 -0.2794)
			(stroke
				(width 0.1)
				(type default)
			)
			(layer "B.Fab")
		)
		(fp_line
			(start -0.67945 -0.3048)
			(end -0.67945 0.3048)
			(stroke
				(width 0.1)
				(type default)
			)
			(layer "B.Fab")
		)
		(fp_line
			(start -0.12065 -0.3048)
			(end -0.67945 -0.3048)
			(stroke
				(width 0.1)
				(type default)
			)
			(layer "B.Fab")
		)
		(fp_line
			(start 0.12065 -0.305054)
			(end 0.12065 -0.2794)
			(stroke
				(width 0.1)
				(type default)
			)
			(layer "B.Fab")
		)
		(fp_line
			(start 0.67945 -0.305054)
			(end 0.12065 -0.305054)
			(stroke
				(width 0.1)
				(type default)
			)
			(layer "B.Fab")
		)
		(pad "1" smd circle
			(at 0.40005 0 90)
			(size 0 0)
			(layers "B.Cu" "B.Mask" "B.Paste")
			(net "NC_PVDDCR_CPU0_P0_IMON9")
		)
		(pad "2" smd circle
			(at -0.40005 0 90)
			(size 0 0)
			(layers "B.Cu" "B.Mask" "B.Paste")
			(net "GND")
		)
	)
)
